# BASEBOARD_FAB2 (Tioga Pass) — schematic netlist excerpt (pin names and nets, part order shuffled) for the footprints in the layout excerpt that follows; sources: Cadence DE-HDL packaged netlist, KiCad conversion of Wiwynn_Tioga_Pass_MB.brd

R7F30  RES  10.0K 1% EMPTY  pkg 0402  page 153 : A = PU_BIOS_SPI_WP0_N ; B = GND
C5A4  CAP_A  47UF 4V 20% X5R  pkg 0603V  page 220 : A = PVDDQ_DEF ; B = GND
R4C2  RES  0.0 5% CHIP  pkg 0402  page 205 : A = VSENSE_PVSA_CPU0_N ; B = VSENSE_PVSA_CPU0_SKT_VRTN

(kicad_pcb
	(version 20260206)
	(generator "pcbnew")
	(generator_version "10.0")
	(general
		(thickness 1.6)
		(legacy_teardrops no)
	)
	(paper "A4")
	(title_block
		(title "Wiwynn_Tioga_Pass_MB.brd")
		(comment 1 "Tioga Pass / footprints 362-364 of 4770")
	)
	(layers
		(0 "F.Cu" signal "TOP")
		(4 "In1.Cu" signal "L2GND")
		(6 "In2.Cu" signal "L3")
		(8 "In3.Cu" signal "L4GND")
		(10 "In4.Cu" signal "L5")
		(12 "In5.Cu" signal "L6GND")
		(14 "In6.Cu" signal "L7VCC")
		(16 "In7.Cu" signal "L8VCC")
		(18 "In8.Cu" signal "L9GND")
		(20 "In9.Cu" signal "L10")
		(22 "In10.Cu" signal "L11GND")
		(24 "In11.Cu" signal "L12")
		(26 "In12.Cu" signal "L13GND")
		(2 "B.Cu" signal "BOTTOM")
		(9 "F.Adhes" user "F.Adhesive")
		(11 "B.Adhes" user "B.Adhesive")
		(13 "F.Paste" user "Package Geometry/Pastemask Top")
		(15 "B.Paste" user "Package Geometry/Pastemask Bottom")
		(5 "F.SilkS" user "Ref Des/Silkscreen Top")
		(7 "B.SilkS" user "Ref Des/Silkscreen Bottom")
		(1 "F.Mask" user "Board Geometry/Soldermask Top")
		(3 "B.Mask" user "Board Geometry/Soldermask Bottom")
		(17 "Dwgs.User" user "User.Drawings")
		(19 "Cmts.User" user "User.Comments")
		(21 "Eco1.User" user "User.Eco1")
		(23 "Eco2.User" user "User.Eco2")
		(25 "Edge.Cuts" user "Board Geometry/Outline")
		(27 "Margin" user)
		(31 "F.CrtYd" user "Package Geometry/Place Bound Top")
		(29 "B.CrtYd" user "Package Geometry/Place Bound Bottom")
		(35 "F.Fab" user "Ref Des/Assembly Top")
		(33 "B.Fab" user "Ref Des/Assembly Bottom")
	)
	(footprint ""
		(layer "F.Cu")
		(at 253.392432 -149.8092 90)
		(property "Reference" "C5A4"
			(at 1.848866 0.752348 90)
			(unlocked yes)
			(layer "F.SilkS")
			(effects
				(font
					(size 1.27 0.9652)
					(thickness 0.1524)
				)
			)
		)
		(property "Value" ""
			(at 0 0 90)
			(layer "F.Fab")
			(effects
				(font
					(size 1.27 1.27)
				)
			)
		)
		(duplicate_pad_numbers_are_jumpers no)
		(fp_rect
			(start -0.500126 1.598422)
			(end 0.500126 -0.201422)
			(stroke
				(width 0)
				(type default)
			)
			(fill no)
			(layer "F.CrtYd")
		)
		(fp_line
			(start 0.500126 -0.201422)
			(end 0.500126 1.598422)
			(stroke
				(width 0.1)
				(type default)
			)
			(layer "F.Fab")
		)
		(fp_line
			(start -0.500126 -0.201422)
			(end 0.500126 -0.201422)
			(stroke
				(width 0.1)
				(type default)
			)
			(layer "F.Fab")
		)
		(fp_line
			(start 0.500126 1.598422)
			(end -0.500126 1.598422)
			(stroke
				(width 0.1)
				(type default)
			)
			(layer "F.Fab")
		)
		(fp_line
			(start -0.500126 1.598422)
			(end -0.500126 -0.201422)
			(stroke
				(width 0.1)
				(type default)
			)
			(layer "F.Fab")
		)
		(pad "1" smd rect
			(at 0 0)
			(size 0.889 0.9906)
			(layers "F.Cu" "F.Mask" "F.Paste")
			(net "PVDDQ_DEF")
		)
		(pad "2" smd rect
			(at 0 1.397)
			(size 0.889 0.9906)
			(layers "F.Cu" "F.Mask" "F.Paste")
			(net "GND")
		)
		(zone
			(layer "F.Cu")
			(hatch none 0.5)
			(connect_pads
				(clearance 0)
			)
			(min_thickness 0.25)
			(keepout
				(tracks not_allowed)
				(vias allowed)
				(pads allowed)
				(copperpour not_allowed)
				(footprints allowed)
			)
			(placement
				(enabled no)
				(sheetname "")
			)
			(fill
				(thermal_gap 0.5)
				(thermal_bridge_width 0.5)
				(island_removal_mode 0)
			)
			(polygon
				(pts
					(xy 254.344932 -149.3139) (xy 254.344932 -150.3045) (xy 253.836932 -150.3045) (xy 253.836932 -149.3139)
				)
			)
		)
		(zone
			(layer "F.Cu")
			(hatch none 0.5)
			(connect_pads
				(clearance 0)
			)
			(min_thickness 0.25)
			(keepout
				(tracks allowed)
				(vias not_allowed)
				(pads allowed)
				(copperpour not_allowed)
				(footprints allowed)
			)
			(placement
				(enabled no)
				(sheetname "")
			)
			(fill
				(thermal_gap 0.5)
				(thermal_bridge_width 0.5)
				(island_removal_mode 0)
			)
			(polygon
				(pts
					(xy 254.344932 -149.3139) (xy 254.344932 -150.3045) (xy 253.836932 -150.3045) (xy 253.836932 -149.3139)
				)
			)
		)
	)
	(footprint ""
		(layer "F.Cu")
		(at 206.248 -103.505 90)
		(property "Reference" "R4C2"
			(at 0 0 90)
			(layer "F.SilkS")
			(hide yes)
			(effects
				(font
					(size 1.27 1.27)
				)
			)
		)
		(property "Value" ""
			(at 0 0 90)
			(layer "F.Fab")
			(effects
				(font
					(size 1.27 1.27)
				)
			)
		)
		(duplicate_pad_numbers_are_jumpers no)
		(fp_poly
			(pts
				(xy -0.2794 -0.1016) (xy 0.2794 -0.1016) (xy 0.2794 0.9906) (xy -0.2794 0.9906)
			)
			(stroke
				(width 0)
				(type default)
			)
			(fill no)
			(layer "F.CrtYd")
		)
		(fp_line
			(start 0.2794 -0.1016)
			(end -0.2794 -0.1016)
			(stroke
				(width 0.1)
				(type default)
			)
			(layer "F.Fab")
		)
		(fp_line
			(start -0.2794 -0.1016)
			(end -0.2794 0.9906)
			(stroke
				(width 0.1)
				(type default)
			)
			(layer "F.Fab")
		)
		(fp_line
			(start 0.2794 0.9906)
			(end 0.2794 -0.1016)
			(stroke
				(width 0.1)
				(type default)
			)
			(layer "F.Fab")
		)
		(fp_line
			(start -0.2794 0.9906)
			(end 0.2794 0.9906)
			(stroke
				(width 0.1)
				(type default)
			)
			(layer "F.Fab")
		)
		(pad "1" smd rect
			(at 0 0 90)
			(size 0.508 0.508)
			(layers "F.Cu" "F.Mask" "F.Paste")
			(net "VSENSE_PVSA_CPU0_N")
		)
		(pad "2" smd rect
			(at 0 0.889 90)
			(size 0.508 0.508)
			(layers "F.Cu" "F.Mask" "F.Paste")
			(net "VSENSE_PVSA_CPU0_SKT_VRTN")
		)
		(zone
			(layer "F.Cu")
			(hatch none 0.5)
			(connect_pads
				(clearance 0)
			)
			(min_thickness 0.25)
			(keepout
				(tracks allowed)
				(vias not_allowed)
				(pads allowed)
				(copperpour not_allowed)
				(footprints allowed)
			)
			(placement
				(enabled no)
				(sheetname "")
			)
			(fill
				(thermal_gap 0.5)
				(thermal_bridge_width 0.5)
				(island_removal_mode 0)
			)
			(polygon
				(pts
					(xy 206.502 -103.251) (xy 206.502 -103.759) (xy 206.883 -103.759) (xy 206.883 -103.251)
				)
			)
		)
		(zone
			(layer "F.Cu")
			(hatch none 0.5)
			(connect_pads
				(clearance 0)
			)
			(min_thickness 0.25)
			(keepout
				(tracks not_allowed)
				(vias allowed)
				(pads allowed)
				(copperpour not_allowed)
				(footprints allowed)
			)
			(placement
				(enabled no)
				(sheetname "")
			)
			(fill
				(thermal_gap 0.5)
				(thermal_bridge_width 0.5)
				(island_removal_mode 0)
			)
			(polygon
				(pts
					(xy 206.883 -103.251) (xy 206.883 -103.759) (xy 206.502 -103.759) (xy 206.502 -103.251)
				)
			)
		)
	)
	(footprint ""
		(layer "F.Cu")
		(at 385.572 -56.3245)
		(property "Reference" "R7F30"
			(at 0 0 0)
			(layer "F.SilkS")
			(hide yes)
			(effects
				(font
					(size 1.27 1.27)
				)
			)
		)
		(property "Value" ""
			(at 0 0 0)
			(layer "F.Fab")
			(effects
				(font
					(size 1.27 1.27)
				)
			)
		)
		(duplicate_pad_numbers_are_jumpers no)
		(fp_poly
			(pts
				(xy -0.2794 -0.1016) (xy 0.2794 -0.1016) (xy 0.2794 0.9906) (xy -0.2794 0.9906)
			)
			(stroke
				(width 0)
				(type default)
			)
			(fill no)
			(layer "F.CrtYd")
		)
		(fp_line
			(start -0.2794 -0.1016)
			(end -0.2794 0.9906)
			(stroke
				(width 0.1)
				(type default)
			)
			(layer "F.Fab")
		)
		(fp_line
			(start -0.2794 0.9906)
			(end 0.2794 0.9906)
			(stroke
				(width 0.1)
				(type default)
			)
			(layer "F.Fab")
		)
		(fp_line
			(start 0.2794 -0.1016)
			(end -0.2794 -0.1016)
			(stroke
				(width 0.1)
				(type default)
			)
			(layer "F.Fab")
		)
		(fp_line
			(start 0.2794 0.9906)
			(end 0.2794 -0.1016)
			(stroke
				(width 0.1)
				(type default)
			)
			(layer "F.Fab")
		)
		(pad "1" smd rect
			(at 0 0)
			(size 0.508 0.508)
			(layers "F.Cu" "F.Mask" "F.Paste")
			(net "PU_BIOS_SPI_WP0_N")
		)
		(pad "2" smd rect
			(at 0 0.889)
			(size 0.508 0.508)
			(layers "F.Cu" "F.Mask" "F.Paste")
			(net "GND")
		)
		(zone
			(layer "F.Cu")
			(hatch none 0.5)
			(connect_pads
				(clearance 0)
			)
			(min_thickness 0.25)
			(keepout
				(tracks allowed)
				(vias not_allowed)
				(pads allowed)
				(copperpour not_allowed)
				(footprints allowed)
			)
			(placement
				(enabled no)
				(sheetname "")
			)
			(fill
				(thermal_gap 0.5)
				(thermal_bridge_width 0.5)
				(island_removal_mode 0)
			)
			(polygon
				(pts
					(xy 385.318 -56.0705) (xy 385.826 -56.0705) (xy 385.826 -55.6895) (xy 385.318 -55.6895)
				)
			)
		)
		(zone
			(layer "F.Cu")
			(hatch none 0.5)
			(connect_pads
				(clearance 0)
			)
			(min_thickness 0.25)
			(keepout
				(tracks not_allowed)
				(vias allowed)
				(pads allowed)
				(copperpour not_allowed)
				(footprints allowed)
			)
			(placement
				(enabled no)
				(sheetname "")
			)
			(fill
				(thermal_gap 0.5)
				(thermal_bridge_width 0.5)
				(island_removal_mode 0)
			)
			(polygon
				(pts
					(xy 385.318 -55.6895) (xy 385.826 -55.6895) (xy 385.826 -56.0705) (xy 385.318 -56.0705)
				)
			)
		)
	)
)
